# T6G (Grand Teton) — schematic netlist excerpt (pin names and nets, part order shuffled) for the footprints in the layout excerpt that follows; sources: Cadence DE-HDL packaged netlist, KiCad conversion of 04192023_DAF0TMB3IC0_F0TG_MB_C_brd_V02_OCP.brd

R2695  Q_RES  1K 1% EMPTY  pkg 0402LF  page 245 : A = P3V3_AUX ; B = TCA9539_0_ADD0
PR161  Q_RES  49.9 1% CHIP  pkg 0402LF  page 210 : A = PVDDCR_CPU0_P1 ; B = VSENSE_PVDDCR_CPU0_P1_DP

(kicad_pcb
	(version 20260206)
	(generator "pcbnew")
	(generator_version "10.0")
	(general
		(thickness 1.6)
		(legacy_teardrops no)
	)
	(paper "A4")
	(title_block
		(title "04192023_DAF0TMB3IC0_F0TG_MB_C_brd_V02_OCP.brd")
		(comment 1 "Grand Teton / footprints 3930-3931 of 8354")
	)
	(layers
		(0 "F.Cu" signal "TOP")
		(4 "In1.Cu" signal "GND")
		(6 "In2.Cu" signal "IN1")
		(8 "In3.Cu" signal "GND1")
		(10 "In4.Cu" signal "IN2")
		(12 "In5.Cu" signal "GND2")
		(14 "In6.Cu" signal "IN3")
		(16 "In7.Cu" signal "GND3")
		(18 "In8.Cu" signal "VCC")
		(20 "In9.Cu" signal "VCC1")
		(22 "In10.Cu" signal "GND4")
		(24 "In11.Cu" signal "IN4")
		(26 "In12.Cu" signal "GND5")
		(28 "In13.Cu" signal "IN5")
		(30 "In14.Cu" signal "GND6")
		(32 "In15.Cu" signal "IN6")
		(34 "In16.Cu" signal "GND7")
		(2 "B.Cu" signal "BOTTOM")
		(9 "F.Adhes" user "F.Adhesive")
		(11 "B.Adhes" user "B.Adhesive")
		(13 "F.Paste" user "Package Geometry/Pastemask Top")
		(15 "B.Paste" user "Package Geometry/Pastemask Bottom")
		(5 "F.SilkS" user "Ref Des/Silkscreen Top")
		(7 "B.SilkS" user "Ref Des/Silkscreen Bottom")
		(1 "F.Mask" user "Board Geometry/Soldermask Top")
		(3 "B.Mask" user "Board Geometry/Soldermask Bottom")
		(17 "Dwgs.User" user "User.Drawings")
		(19 "Cmts.User" user "User.Comments")
		(21 "Eco1.User" user "User.Eco1")
		(23 "Eco2.User" user "User.Eco2")
		(25 "Edge.Cuts" user "Board Geometry/Outline")
		(27 "Margin" user)
		(31 "F.CrtYd" user "Package Geometry/Place Bound Top")
		(29 "B.CrtYd" user "Package Geometry/Place Bound Bottom")
		(35 "F.Fab" user "Ref Des/Assembly Top")
		(33 "B.Fab" user "Ref Des/Assembly Bottom")
	)
	(footprint ""
		(layer "F.Cu")
		(at 177.378106 -426.332396)
		(property "Reference" "R2695"
			(at 0 0 0)
			(layer "F.SilkS")
			(hide yes)
			(effects
				(font
					(size 1.27 1.27)
				)
			)
		)
		(property "Value" ""
			(at 0 0 0)
			(layer "F.Fab")
			(effects
				(font
					(size 1.27 1.27)
				)
			)
		)
		(duplicate_pad_numbers_are_jumpers no)
		(fp_line
			(start -0.7874 -0.4064)
			(end 0.7874 -0.4064)
			(stroke
				(width 0.1524)
				(type default)
			)
			(layer "F.SilkS")
		)
		(fp_line
			(start -0.7874 0.4064)
			(end -0.7874 -0.4064)
			(stroke
				(width 0.1524)
				(type default)
			)
			(layer "F.SilkS")
		)
		(fp_line
			(start 0.7874 -0.4064)
			(end 0.7874 0.4064)
			(stroke
				(width 0.1524)
				(type default)
			)
			(layer "F.SilkS")
		)
		(fp_line
			(start 0.7874 0.4064)
			(end -0.7874 0.4064)
			(stroke
				(width 0.1524)
				(type default)
			)
			(layer "F.SilkS")
		)
		(fp_line
			(start -0.67945 -0.305054)
			(end -0.12065 -0.305054)
			(stroke
				(width 0.1)
				(type default)
			)
			(layer "F.Fab")
		)
		(fp_line
			(start -0.67945 0.3048)
			(end -0.67945 -0.305054)
			(stroke
				(width 0.1)
				(type default)
			)
			(layer "F.Fab")
		)
		(fp_line
			(start -0.12065 -0.305054)
			(end -0.12065 -0.2794)
			(stroke
				(width 0.1)
				(type default)
			)
			(layer "F.Fab")
		)
		(fp_line
			(start -0.12065 -0.2794)
			(end 0.12065 -0.2794)
			(stroke
				(width 0.1)
				(type default)
			)
			(layer "F.Fab")
		)
		(fp_line
			(start -0.12065 0.2794)
			(end -0.12065 0.3048)
			(stroke
				(width 0.1)
				(type default)
			)
			(layer "F.Fab")
		)
		(fp_line
			(start -0.12065 0.3048)
			(end -0.67945 0.3048)
			(stroke
				(width 0.1)
				(type default)
			)
			(layer "F.Fab")
		)
		(fp_line
			(start 0.120396 0.2794)
			(end -0.12065 0.2794)
			(stroke
				(width 0.1)
				(type default)
			)
			(layer "F.Fab")
		)
		(fp_line
			(start 0.120396 0.3048)
			(end 0.120396 0.2794)
			(stroke
				(width 0.1)
				(type default)
			)
			(layer "F.Fab")
		)
		(fp_line
			(start 0.12065 -0.3048)
			(end 0.67945 -0.3048)
			(stroke
				(width 0.1)
				(type default)
			)
			(layer "F.Fab")
		)
		(fp_line
			(start 0.12065 -0.2794)
			(end 0.12065 -0.3048)
			(stroke
				(width 0.1)
				(type default)
			)
			(layer "F.Fab")
		)
		(fp_line
			(start 0.67945 -0.3048)
			(end 0.67945 0.3048)
			(stroke
				(width 0.1)
				(type default)
			)
			(layer "F.Fab")
		)
		(fp_line
			(start 0.67945 0.3048)
			(end 0.120396 0.3048)
			(stroke
				(width 0.1)
				(type default)
			)
			(layer "F.Fab")
		)
		(pad "1" smd circle
			(at -0.40005 0)
			(size 0 0)
			(layers "F.Cu" "F.Mask" "F.Paste")
			(net "P3V3_AUX")
		)
		(pad "2" smd circle
			(at 0.40005 0)
			(size 0 0)
			(layers "F.Cu" "F.Mask" "F.Paste")
			(net "TCA9539_0_ADD0")
		)
	)
	(footprint ""
		(layer "F.Cu")
		(at 59.497722 -181.819042 180)
		(property "Reference" "PR161"
			(at 0 0 180)
			(layer "F.SilkS")
			(hide yes)
			(effects
				(font
					(size 1.27 1.27)
				)
			)
		)
		(property "Value" ""
			(at 0 0 180)
			(layer "F.Fab")
			(effects
				(font
					(size 1.27 1.27)
				)
			)
		)
		(duplicate_pad_numbers_are_jumpers no)
		(fp_line
			(start 0.7874 0.4064)
			(end -0.7874 0.4064)
			(stroke
				(width 0.1524)
				(type default)
			)
			(layer "F.SilkS")
		)
		(fp_line
			(start 0.7874 -0.4064)
			(end 0.7874 0.4064)
			(stroke
				(width 0.1524)
				(type default)
			)
			(layer "F.SilkS")
		)
		(fp_line
			(start -0.7874 0.4064)
			(end -0.7874 -0.4064)
			(stroke
				(width 0.1524)
				(type default)
			)
			(layer "F.SilkS")
		)
		(fp_line
			(start -0.7874 -0.4064)
			(end 0.7874 -0.4064)
			(stroke
				(width 0.1524)
				(type default)
			)
			(layer "F.SilkS")
		)
		(fp_line
			(start 0.67945 0.3048)
			(end 0.120396 0.3048)
			(stroke
				(width 0.1)
				(type default)
			)
			(layer "F.Fab")
		)
		(fp_line
			(start 0.67945 -0.3048)
			(end 0.67945 0.3048)
			(stroke
				(width 0.1)
				(type default)
			)
			(layer "F.Fab")
		)
		(fp_line
			(start 0.12065 -0.2794)
			(end 0.12065 -0.3048)
			(stroke
				(width 0.1)
				(type default)
			)
			(layer "F.Fab")
		)
		(fp_line
			(start 0.12065 -0.3048)
			(end 0.67945 -0.3048)
			(stroke
				(width 0.1)
				(type default)
			)
			(layer "F.Fab")
		)
		(fp_line
			(start 0.120396 0.3048)
			(end 0.120396 0.2794)
			(stroke
				(width 0.1)
				(type default)
			)
			(layer "F.Fab")
		)
		(fp_line
			(start 0.120396 0.2794)
			(end -0.12065 0.2794)
			(stroke
				(width 0.1)
				(type default)
			)
			(layer "F.Fab")
		)
		(fp_line
			(start -0.12065 0.3048)
			(end -0.67945 0.3048)
			(stroke
				(width 0.1)
				(type default)
			)
			(layer "F.Fab")
		)
		(fp_line
			(start -0.12065 0.2794)
			(end -0.12065 0.3048)
			(stroke
				(width 0.1)
				(type default)
			)
			(layer "F.Fab")
		)
		(fp_line
			(start -0.12065 -0.2794)
			(end 0.12065 -0.2794)
			(stroke
				(width 0.1)
				(type default)
			)
			(layer "F.Fab")
		)
		(fp_line
			(start -0.12065 -0.305054)
			(end -0.12065 -0.2794)
			(stroke
				(width 0.1)
				(type default)
			)
			(layer "F.Fab")
		)
		(fp_line
			(start -0.67945 0.3048)
			(end -0.67945 -0.305054)
			(stroke
				(width 0.1)
				(type default)
			)
			(layer "F.Fab")
		)
		(fp_line
			(start -0.67945 -0.305054)
			(end -0.12065 -0.305054)
			(stroke
				(width 0.1)
				(type default)
			)
			(layer "F.Fab")
		)
		(pad "1" smd circle
			(at -0.40005 0 180)
			(size 0 0)
			(layers "F.Cu" "F.Mask" "F.Paste")
			(net "PVDDCR_CPU0_P1")
		)
		(pad "2" smd circle
			(at 0.40005 0 180)
			(size 0 0)
			(layers "F.Cu" "F.Mask" "F.Paste")
			(net "VSENSE_PVDDCR_CPU0_P1_DP")
		)
	)
)
